(kicad_pcb
	(version 20260206)
	(generator "pcbnew")
	(generator_version "10.0")
	(general
		(thickness 1.6)
		(legacy_teardrops no)
	)
	(paper "A4")
	(title_block
		(title "01162023_DA0F0TEBIF0_F0T_Expander_BD_F_brd_V02_OCP.brd")
		(comment 1 "Grand Teton / footprints 3161-3165 of 9728")
	)
	(layers
		(0 "F.Cu" signal "TOP")
		(4 "In1.Cu" signal "GND")
		(6 "In2.Cu" signal "VCC")
		(8 "In3.Cu" signal "VCC1")
		(10 "In4.Cu" signal "GND1")
		(12 "In5.Cu" signal "IN1")
		(14 "In6.Cu" signal "GND2")
		(16 "In7.Cu" signal "IN2")
		(18 "In8.Cu" signal "GND3")
		(20 "In9.Cu" signal "IN3")
		(22 "In10.Cu" signal "GND4")
		(24 "In11.Cu" signal "IN4")
		(26 "In12.Cu" signal "GND5")
		(28 "In13.Cu" signal "IN5")
		(30 "In14.Cu" signal "GND6")
		(32 "In15.Cu" signal "IN6")
		(34 "In16.Cu" signal "GND7")
		(2 "B.Cu" signal "BOTTOM")
		(9 "F.Adhes" user "F.Adhesive")
		(11 "B.Adhes" user "B.Adhesive")
		(13 "F.Paste" user "Package Geometry/Pastemask Top")
		(15 "B.Paste" user "Package Geometry/Pastemask Bottom")
		(5 "F.SilkS" user "Ref Des/Silkscreen Top")
		(7 "B.SilkS" user "Ref Des/Silkscreen Bottom")
		(1 "F.Mask" user "Board Geometry/Soldermask Top")
		(3 "B.Mask" user "Board Geometry/Soldermask Bottom")
		(17 "Dwgs.User" user "User.Drawings")
		(19 "Cmts.User" user "User.Comments")
		(21 "Eco1.User" user "User.Eco1")
		(23 "Eco2.User" user "User.Eco2")
		(25 "Edge.Cuts" user "Board Geometry/Outline")
		(27 "Margin" user)
		(31 "F.CrtYd" user "Package Geometry/Place Bound Top")
		(29 "B.CrtYd" user "Package Geometry/Place Bound Bottom")
		(35 "F.Fab" user "Ref Des/Assembly Top")
		(33 "B.Fab" user "Ref Des/Assembly Bottom")
	)
	(footprint ""
		(layer "F.Cu")
		(at 426.9105 -18.61439 90)
		(property "Reference" "U140"
			(at -1.44399 2.35077 90)
			(unlocked yes)
			(layer "F.SilkS")
			(effects
				(font
					(size 0.7874 0.5842)
					(thickness 0.1524)
				)
				(justify left)
			)
		)
		(property "Value" ""
			(at 0 0 90)
			(layer "F.Fab")
			(effects
				(font
					(size 1.27 1.27)
				)
			)
		)
		(duplicate_pad_numbers_are_jumpers no)
		(fp_line
			(start 1.463548 -1.549908)
			(end 1.463548 1.549908)
			(stroke
				(width 0.1524)
				(type default)
			)
			(layer "F.SilkS")
		)
		(fp_line
			(start 0.762 -1.549908)
			(end 1.463548 -1.549908)
			(stroke
				(width 0.1524)
				(type default)
			)
			(layer "F.SilkS")
		)
		(fp_line
			(start -0.787908 -1.549908)
			(end 0 -0.762)
			(stroke
				(width 0.1524)
				(type default)
			)
			(layer "F.SilkS")
		)
		(fp_line
			(start -1.463548 -1.549908)
			(end -0.787908 -1.549908)
			(stroke
				(width 0.1524)
				(type default)
			)
			(layer "F.SilkS")
		)
		(fp_line
			(start 0 -0.762)
			(end 0.762 -1.549908)
			(stroke
				(width 0.1524)
				(type default)
			)
			(layer "F.SilkS")
		)
		(fp_line
			(start 1.463548 1.549908)
			(end -1.463548 1.549908)
			(stroke
				(width 0.1524)
				(type default)
			)
			(layer "F.SilkS")
		)
		(fp_line
			(start -1.463548 1.549908)
			(end -1.463548 -1.549908)
			(stroke
				(width 0.1524)
				(type default)
			)
			(layer "F.SilkS")
		)
		(fp_poly
			(pts
				(xy -3.4798 -1.359916) (xy -2.86004 -1.050036) (xy -3.4798 -0.740156)
			)
			(stroke
				(width 0)
				(type default)
			)
			(fill yes)
			(layer "F.SilkS")
		)
		(fp_line
			(start 1.549908 -1.549908)
			(end 1.549908 1.549908)
			(stroke
				(width 0.1)
				(type default)
			)
			(layer "F.Fab")
		)
		(fp_line
			(start -1.549908 -1.549908)
			(end 1.549908 -1.549908)
			(stroke
				(width 0.1)
				(type default)
			)
			(layer "F.Fab")
		)
		(fp_line
			(start 1.549908 1.549908)
			(end -1.549908 1.549908)
			(stroke
				(width 0.1)
				(type default)
			)
			(layer "F.Fab")
		)
		(fp_line
			(start -1.549908 1.549908)
			(end -1.549908 -1.549908)
			(stroke
				(width 0.1)
				(type default)
			)
			(layer "F.Fab")
		)
		(fp_poly
			(pts
				(xy -3.4798 -1.359916) (xy -2.86004 -1.050036) (xy -3.4798 -0.740156)
			)
			(stroke
				(width 0)
				(type default)
			)
			(fill yes)
			(layer "F.Fab")
		)
		(pad "1" smd rect
			(at -2.175002 -1.050036 180)
			(size 0.6096 1.1684)
			(layers "F.Cu" "F.Mask" "F.Paste")
			(net "P3V3_SSD14")
		)
		(pad "2" smd rect
			(at -2.175002 -0.32512 180)
			(size 0.4318 1.1684)
			(layers "F.Cu" "F.Mask" "F.Paste")
			(net "SMB_ISO_SSD14_SCL")
		)
		(pad "3" smd rect
			(at -2.175002 0.32512 180)
			(size 0.4318 1.1684)
			(layers "F.Cu" "F.Mask" "F.Paste")
			(net "SMB_ISO_SSD14_SDA")
		)
		(pad "4" smd rect
			(at -2.175002 1.050036 180)
			(size 0.6096 1.1684)
			(layers "F.Cu" "F.Mask" "F.Paste")
			(net "GND")
		)
		(pad "5" smd rect
			(at 2.175002 1.050036 180)
			(size 0.6096 1.1684)
			(layers "F.Cu" "F.Mask" "F.Paste")
			(net "SMB_SSD14_ISO_EN")
		)
		(pad "6" smd rect
			(at 2.175002 0.32512 180)
			(size 0.4318 1.1684)
			(layers "F.Cu" "F.Mask" "F.Paste")
			(net "SMB_BIC_I2C9_MUX1_SSD14_R_SDA")
		)
		(pad "7" smd rect
			(at 2.175002 -0.32512 180)
			(size 0.4318 1.1684)
			(layers "F.Cu" "F.Mask" "F.Paste")
			(net "SMB_BIC_I2C9_MUX1_SSD14_R_SCL")
		)
		(pad "8" smd rect
			(at 2.175002 -1.050036 180)
			(size 0.6096 1.1684)
			(layers "F.Cu" "F.Mask" "F.Paste")
			(net "P3V3_AUX")
		)
	)
	(footprint ""
		(layer "F.Cu")
		(at 98.048318 -392.0998)
		(property "Reference" "R5450"
			(at 0 0 0)
			(layer "F.SilkS")
			(hide yes)
			(effects
				(font
					(size 1.27 1.27)
				)
			)
		)
		(property "Value" ""
			(at 0 0 0)
			(layer "F.Fab")
			(effects
				(font
					(size 1.27 1.27)
				)
			)
		)
		(duplicate_pad_numbers_are_jumpers no)
		(fp_line
			(start -0.7874 -0.4064)
			(end 0.7874 -0.4064)
			(stroke
				(width 0.1524)
				(type default)
			)
			(layer "F.SilkS")
		)
		(fp_line
			(start -0.7874 0.4064)
			(end -0.7874 -0.4064)
			(stroke
				(width 0.1524)
				(type default)
			)
			(layer "F.SilkS")
		)
		(fp_line
			(start 0.7874 -0.4064)
			(end 0.7874 0.4064)
			(stroke
				(width 0.1524)
				(type default)
			)
			(layer "F.SilkS")
		)
		(fp_line
			(start 0.7874 0.4064)
			(end -0.7874 0.4064)
			(stroke
				(width 0.1524)
				(type default)
			)
			(layer "F.SilkS")
		)
		(fp_line
			(start -0.67945 -0.305054)
			(end -0.12065 -0.305054)
			(stroke
				(width 0.1)
				(type default)
			)
			(layer "F.Fab")
		)
		(fp_line
			(start -0.67945 0.3048)
			(end -0.67945 -0.305054)
			(stroke
				(width 0.1)
				(type default)
			)
			(layer "F.Fab")
		)
		(fp_line
			(start -0.12065 -0.305054)
			(end -0.12065 -0.2794)
			(stroke
				(width 0.1)
				(type default)
			)
			(layer "F.Fab")
		)
		(fp_line
			(start -0.12065 -0.2794)
			(end 0.12065 -0.2794)
			(stroke
				(width 0.1)
				(type default)
			)
			(layer "F.Fab")
		)
		(fp_line
			(start -0.12065 0.2794)
			(end -0.12065 0.3048)
			(stroke
				(width 0.1)
				(type default)
			)
			(layer "F.Fab")
		)
		(fp_line
			(start -0.12065 0.3048)
			(end -0.67945 0.3048)
			(stroke
				(width 0.1)
				(type default)
			)
			(layer "F.Fab")
		)
		(fp_line
			(start 0.120396 0.2794)
			(end -0.12065 0.2794)
			(stroke
				(width 0.1)
				(type default)
			)
			(layer "F.Fab")
		)
		(fp_line
			(start 0.120396 0.3048)
			(end 0.120396 0.2794)
			(stroke
				(width 0.1)
				(type default)
			)
			(layer "F.Fab")
		)
		(fp_line
			(start 0.12065 -0.3048)
			(end 0.67945 -0.3048)
			(stroke
				(width 0.1)
				(type default)
			)
			(layer "F.Fab")
		)
		(fp_line
			(start 0.12065 -0.2794)
			(end 0.12065 -0.3048)
			(stroke
				(width 0.1)
				(type default)
			)
			(layer "F.Fab")
		)
		(fp_line
			(start 0.67945 -0.3048)
			(end 0.67945 0.3048)
			(stroke
				(width 0.1)
				(type default)
			)
			(layer "F.Fab")
		)
		(fp_line
			(start 0.67945 0.3048)
			(end 0.120396 0.3048)
			(stroke
				(width 0.1)
				(type default)
			)
			(layer "F.Fab")
		)
		(pad "1" smd circle
			(at -0.40005 0)
			(size 0 0)
			(layers "F.Cu" "F.Mask" "F.Paste")
			(net "P3V3_AUX")
		)
		(pad "2" smd circle
			(at 0.40005 0)
			(size 0 0)
			(layers "F.Cu" "F.Mask" "F.Paste")
			(net "BIC_USB_HUB_OVCUR2")
		)
	)
	(footprint ""
		(layer "F.Cu")
		(at 211.177886 -233.881422 -90)
		(property "Reference" "R1547"
			(at 0 0 270)
			(layer "F.SilkS")
			(hide yes)
			(effects
				(font
					(size 1.27 1.27)
				)
			)
		)
		(property "Value" ""
			(at 0 0 270)
			(layer "F.Fab")
			(effects
				(font
					(size 1.27 1.27)
				)
			)
		)
		(duplicate_pad_numbers_are_jumpers no)
		(fp_line
			(start -0.7874 0.4064)
			(end -0.7874 -0.4064)
			(stroke
				(width 0.1524)
				(type default)
			)
			(layer "F.SilkS")
		)
		(fp_line
			(start 0.7874 0.4064)
			(end -0.7874 0.4064)
			(stroke
				(width 0.1524)
				(type default)
			)
			(layer "F.SilkS")
		)
		(fp_line
			(start -0.7874 -0.4064)
			(end 0.7874 -0.4064)
			(stroke
				(width 0.1524)
				(type default)
			)
			(layer "F.SilkS")
		)
		(fp_line
			(start 0.7874 -0.4064)
			(end 0.7874 0.4064)
			(stroke
				(width 0.1524)
				(type default)
			)
			(layer "F.SilkS")
		)
		(fp_line
			(start -0.67945 0.3048)
			(end -0.67945 -0.305054)
			(stroke
				(width 0.1)
				(type default)
			)
			(layer "F.Fab")
		)
		(fp_line
			(start -0.12065 0.3048)
			(end -0.67945 0.3048)
			(stroke
				(width 0.1)
				(type default)
			)
			(layer "F.Fab")
		)
		(fp_line
			(start 0.120396 0.3048)
			(end 0.120396 0.2794)
			(stroke
				(width 0.1)
				(type default)
			)
			(layer "F.Fab")
		)
		(fp_line
			(start 0.67945 0.3048)
			(end 0.120396 0.3048)
			(stroke
				(width 0.1)
				(type default)
			)
			(layer "F.Fab")
		)
		(fp_line
			(start -0.12065 0.2794)
			(end -0.12065 0.3048)
			(stroke
				(width 0.1)
				(type default)
			)
			(layer "F.Fab")
		)
		(fp_line
			(start 0.120396 0.2794)
			(end -0.12065 0.2794)
			(stroke
				(width 0.1)
				(type default)
			)
			(layer "F.Fab")
		)
		(fp_line
			(start -0.12065 -0.2794)
			(end 0.12065 -0.2794)
			(stroke
				(width 0.1)
				(type default)
			)
			(layer "F.Fab")
		)
		(fp_line
			(start 0.12065 -0.2794)
			(end 0.12065 -0.3048)
			(stroke
				(width 0.1)
				(type default)
			)
			(layer "F.Fab")
		)
		(fp_line
			(start 0.12065 -0.3048)
			(end 0.67945 -0.3048)
			(stroke
				(width 0.1)
				(type default)
			)
			(layer "F.Fab")
		)
		(fp_line
			(start 0.67945 -0.3048)
			(end 0.67945 0.3048)
			(stroke
				(width 0.1)
				(type default)
			)
			(layer "F.Fab")
		)
		(fp_line
			(start -0.67945 -0.305054)
			(end -0.12065 -0.305054)
			(stroke
				(width 0.1)
				(type default)
			)
			(layer "F.Fab")
		)
		(fp_line
			(start -0.12065 -0.305054)
			(end -0.12065 -0.2794)
			(stroke
				(width 0.1)
				(type default)
			)
			(layer "F.Fab")
		)
		(pad "1" smd circle
			(at -0.40005 0 270)
			(size 0 0)
			(layers "F.Cu" "F.Mask" "F.Paste")
			(net "SMB_PEX_LS_R_SCL")
		)
		(pad "2" smd circle
			(at 0.40005 0 270)
			(size 0 0)
			(layers "F.Cu" "F.Mask" "F.Paste")
			(net "SMB_PEX2_SCL")
		)
	)
	(footprint ""
		(layer "F.Cu")
		(at 378.673868 -27.006296 -90)
		(property "Reference" "PC964"
			(at 0 0 270)
			(layer "F.SilkS")
			(hide yes)
			(effects
				(font
					(size 1.27 1.27)
				)
			)
		)
		(property "Value" ""
			(at 0 0 270)
			(layer "F.Fab")
			(effects
				(font
					(size 1.27 1.27)
				)
			)
		)
		(duplicate_pad_numbers_are_jumpers no)
		(fp_line
			(start -0.7874 0.4064)
			(end -0.7874 -0.4064)
			(stroke
				(width 0.1524)
				(type default)
			)
			(layer "F.SilkS")
		)
		(fp_line
			(start 0.7874 0.4064)
			(end -0.7874 0.4064)
			(stroke
				(width 0.1524)
				(type default)
			)
			(layer "F.SilkS")
		)
		(fp_line
			(start -0.7874 -0.4064)
			(end 0.7874 -0.4064)
			(stroke
				(width 0.1524)
				(type default)
			)
			(layer "F.SilkS")
		)
		(fp_line
			(start 0.7874 -0.4064)
			(end 0.7874 0.4064)
			(stroke
				(width 0.1524)
				(type default)
			)
			(layer "F.SilkS")
		)
		(fp_line
			(start -0.67945 0.3048)
			(end -0.67945 -0.305054)
			(stroke
				(width 0.1)
				(type default)
			)
			(layer "F.Fab")
		)
		(fp_line
			(start -0.12065 0.3048)
			(end -0.67945 0.3048)
			(stroke
				(width 0.1)
				(type default)
			)
			(layer "F.Fab")
		)
		(fp_line
			(start 0.120396 0.3048)
			(end 0.120396 0.2794)
			(stroke
				(width 0.1)
				(type default)
			)
			(layer "F.Fab")
		)
		(fp_line
			(start 0.67945 0.3048)
			(end 0.120396 0.3048)
			(stroke
				(width 0.1)
				(type default)
			)
			(layer "F.Fab")
		)
		(fp_line
			(start -0.12065 0.2794)
			(end -0.12065 0.3048)
			(stroke
				(width 0.1)
				(type default)
			)
			(layer "F.Fab")
		)
		(fp_line
			(start 0.120396 0.2794)
			(end -0.12065 0.2794)
			(stroke
				(width 0.1)
				(type default)
			)
			(layer "F.Fab")
		)
		(fp_line
			(start -0.12065 -0.2794)
			(end 0.12065 -0.2794)
			(stroke
				(width 0.1)
				(type default)
			)
			(layer "F.Fab")
		)
		(fp_line
			(start 0.12065 -0.2794)
			(end 0.12065 -0.3048)
			(stroke
				(width 0.1)
				(type default)
			)
			(layer "F.Fab")
		)
		(fp_line
			(start 0.12065 -0.3048)
			(end 0.67945 -0.3048)
			(stroke
				(width 0.1)
				(type default)
			)
			(layer "F.Fab")
		)
		(fp_line
			(start 0.67945 -0.3048)
			(end 0.67945 0.3048)
			(stroke
				(width 0.1)
				(type default)
			)
			(layer "F.Fab")
		)
		(fp_line
			(start -0.67945 -0.305054)
			(end -0.12065 -0.305054)
			(stroke
				(width 0.1)
				(type default)
			)
			(layer "F.Fab")
		)
		(fp_line
			(start -0.12065 -0.305054)
			(end -0.12065 -0.2794)
			(stroke
				(width 0.1)
				(type default)
			)
			(layer "F.Fab")
		)
		(pad "1" smd circle
			(at -0.40005 0 270)
			(size 0 0)
			(layers "F.Cu" "F.Mask" "F.Paste")
			(net "P3V3_SSD13_CO_MODE")
		)
		(pad "2" smd circle
			(at 0.40005 0 270)
			(size 0 0)
			(layers "F.Cu" "F.Mask" "F.Paste")
			(net "GND")
		)
	)
	(footprint ""
		(layer "F.Cu")
		(at 38.875208 -343.952322 90)
		(property "Reference" "C2169"
			(at 0 0 90)
			(layer "F.SilkS")
			(hide yes)
			(effects
				(font
					(size 1.27 1.27)
				)
			)
		)
		(property "Value" ""
			(at 0 0 90)
			(layer "F.Fab")
			(effects
				(font
					(size 1.27 1.27)
				)
			)
		)
		(duplicate_pad_numbers_are_jumpers no)
		(fp_line
			(start 0.299974 -0.150114)
			(end 0.299974 0.150114)
			(stroke
				(width 0.1)
				(type default)
			)
			(layer "F.Fab")
		)
		(fp_line
			(start -0.299974 -0.150114)
			(end 0.299974 -0.150114)
			(stroke
				(width 0.1)
				(type default)
			)
			(layer "F.Fab")
		)
		(fp_line
			(start 0.299974 0.150114)
			(end -0.299974 0.150114)
			(stroke
				(width 0.1)
				(type default)
			)
			(layer "F.Fab")
		)
		(fp_line
			(start -0.299974 0.150114)
			(end -0.299974 -0.150114)
			(stroke
				(width 0.1)
				(type default)
			)
			(layer "F.Fab")
		)
		(pad "1" smd rect
			(at -0.2667 0 90)
			(size 0.3048 0.381)
			(layers "F.Cu" "F.Mask" "F.Paste")
			(net "P5E_PEX0_STN4_TX_DN<71>")
		)
		(pad "2" smd rect
			(at 0.2667 0 90)
			(size 0.3048 0.381)
			(layers "F.Cu" "F.Mask" "F.Paste")
			(net "P5E_PEX0_STN4_TX_C_DN<71>")
		)
	)
)
